(kicad_pcb
	(version 20260206)
	(generator "pcbnew")
	(generator_version "10.0")
	(general
		(thickness 1.6)
		(legacy_teardrops no)
	)
	(paper "A4")
	(title_block
		(title "04192023_DAF0TMB3IC0_F0TG_MB_C_brd_V02_OCP.brd")
		(comment 1 "Grand Teton / footprint 34 of 8354 (J37), pads 1-113 of 291")
	)
	(layers
		(0 "F.Cu" signal "TOP")
		(4 "In1.Cu" signal "GND")
		(6 "In2.Cu" signal "IN1")
		(8 "In3.Cu" signal "GND1")
		(10 "In4.Cu" signal "IN2")
		(12 "In5.Cu" signal "GND2")
		(14 "In6.Cu" signal "IN3")
		(16 "In7.Cu" signal "GND3")
		(18 "In8.Cu" signal "VCC")
		(20 "In9.Cu" signal "VCC1")
		(22 "In10.Cu" signal "GND4")
		(24 "In11.Cu" signal "IN4")
		(26 "In12.Cu" signal "GND5")
		(28 "In13.Cu" signal "IN5")
		(30 "In14.Cu" signal "GND6")
		(32 "In15.Cu" signal "IN6")
		(34 "In16.Cu" signal "GND7")
		(2 "B.Cu" signal "BOTTOM")
		(9 "F.Adhes" user "F.Adhesive")
		(11 "B.Adhes" user "B.Adhesive")
		(13 "F.Paste" user "Package Geometry/Pastemask Top")
		(15 "B.Paste" user "Package Geometry/Pastemask Bottom")
		(5 "F.SilkS" user "Ref Des/Silkscreen Top")
		(7 "B.SilkS" user "Ref Des/Silkscreen Bottom")
		(1 "F.Mask" user "Board Geometry/Soldermask Top")
		(3 "B.Mask" user "Board Geometry/Soldermask Bottom")
		(17 "Dwgs.User" user "User.Drawings")
		(19 "Cmts.User" user "User.Comments")
		(21 "Eco1.User" user "User.Eco1")
		(23 "Eco2.User" user "User.Eco2")
		(25 "Edge.Cuts" user "Board Geometry/Outline")
		(27 "Margin" user)
		(31 "F.CrtYd" user "Package Geometry/Place Bound Top")
		(29 "B.CrtYd" user "Package Geometry/Place Bound Bottom")
		(35 "F.Fab" user "Ref Des/Assembly Top")
		(33 "B.Fab" user "Ref Des/Assembly Bottom")
	)
	(footprint ""
		(layer "F.Cu")
		(at 204.197966 -255.560322 180)
		(property "Reference" "J37"
			(at 2.8702 -81.730088 0)
			(unlocked yes)
			(layer "F.SilkS")
			(effects
				(font
					(size 0.7874 0.5842)
					(thickness 0.1524)
				)
			)
		)
		(property "Value" ""
			(at 0 0 180)
			(layer "F.Fab")
			(effects
				(font
					(size 1.27 1.27)
				)
			)
		)
		(duplicate_pad_numbers_are_jumpers no)
		(pad "1" smd rect
			(at -2.050034 -63.324994 90)
			(size 0.519938 1.4986)
			(layers "F.Cu" "F.Mask" "F.Paste")
			(net "P12V_MEM_CPU1")
		)
		(pad "2" smd rect
			(at -2.050034 -62.47511 90)
			(size 0.519938 1.4986)
			(layers "F.Cu" "F.Mask" "F.Paste")
			(net "Net_2410")
		)
		(pad "3" smd rect
			(at -2.050034 -61.624972 90)
			(size 0.519938 1.4986)
			(layers "F.Cu" "F.Mask" "F.Paste")
			(net "P3V3_AUX")
		)
		(pad "4" smd rect
			(at -2.050034 -60.775088 90)
			(size 0.519938 1.4986)
			(layers "F.Cu" "F.Mask" "F.Paste")
			(net "I3C_SPD_DDRL_CPU1_SCL")
		)
		(pad "5" smd rect
			(at -2.050034 -59.92495 90)
			(size 0.519938 1.4986)
			(layers "F.Cu" "F.Mask" "F.Paste")
			(net "I3C_SPD_DDRL_CPU1_SDA")
		)
		(pad "6" smd rect
			(at -2.050034 -59.075066 90)
			(size 0.519938 1.4986)
			(layers "F.Cu" "F.Mask" "F.Paste")
			(net "GND")
		)
		(pad "7" smd rect
			(at -2.050034 -58.224928 90)
			(size 0.519938 1.4986)
			(layers "F.Cu" "F.Mask" "F.Paste")
			(net "M_L_CPU1_SA_DQ<0>")
		)
		(pad "8" smd rect
			(at -2.050034 -57.375044 90)
			(size 0.519938 1.4986)
			(layers "F.Cu" "F.Mask" "F.Paste")
			(net "GND")
		)
		(pad "9" smd rect
			(at -2.050034 -56.524906 90)
			(size 0.519938 1.4986)
			(layers "F.Cu" "F.Mask" "F.Paste")
			(net "M_L_CPU1_SA_DQ<1>")
		)
		(pad "10" smd rect
			(at -2.050034 -55.675022 90)
			(size 0.519938 1.4986)
			(layers "F.Cu" "F.Mask" "F.Paste")
			(net "GND")
		)
		(pad "11" smd rect
			(at -2.050034 -54.824884 90)
			(size 0.519938 1.4986)
			(layers "F.Cu" "F.Mask" "F.Paste")
			(net "M_L_CPU1_SA_DQS_DP<0>")
		)
		(pad "12" smd rect
			(at -2.050034 -53.975 90)
			(size 0.519938 1.4986)
			(layers "F.Cu" "F.Mask" "F.Paste")
			(net "M_L_CPU1_SA_DQS_DN<0>")
		)
		(pad "13" smd rect
			(at -2.050034 -53.125116 90)
			(size 0.519938 1.4986)
			(layers "F.Cu" "F.Mask" "F.Paste")
			(net "GND")
		)
		(pad "14" smd rect
			(at -2.050034 -52.274978 90)
			(size 0.519938 1.4986)
			(layers "F.Cu" "F.Mask" "F.Paste")
			(net "M_L_CPU1_SA_DQ<4>")
		)
		(pad "15" smd rect
			(at -2.050034 -51.425094 90)
			(size 0.519938 1.4986)
			(layers "F.Cu" "F.Mask" "F.Paste")
			(net "GND")
		)
		(pad "16" smd rect
			(at -2.050034 -50.574956 90)
			(size 0.519938 1.4986)
			(layers "F.Cu" "F.Mask" "F.Paste")
			(net "M_L_CPU1_SA_DQ<5>")
		)
		(pad "17" smd rect
			(at -2.050034 -49.725072 90)
			(size 0.519938 1.4986)
			(layers "F.Cu" "F.Mask" "F.Paste")
			(net "GND")
		)
		(pad "18" smd rect
			(at -2.050034 -48.874934 90)
			(size 0.519938 1.4986)
			(layers "F.Cu" "F.Mask" "F.Paste")
			(net "M_L_CPU1_SA_DQ<8>")
		)
		(pad "19" smd rect
			(at -2.050034 -48.02505 90)
			(size 0.519938 1.4986)
			(layers "F.Cu" "F.Mask" "F.Paste")
			(net "GND")
		)
		(pad "20" smd rect
			(at -2.050034 -47.174912 90)
			(size 0.519938 1.4986)
			(layers "F.Cu" "F.Mask" "F.Paste")
			(net "M_L_CPU1_SA_DQ<9>")
		)
		(pad "21" smd rect
			(at -2.050034 -46.325028 90)
			(size 0.519938 1.4986)
			(layers "F.Cu" "F.Mask" "F.Paste")
			(net "GND")
		)
		(pad "22" smd rect
			(at -2.050034 -45.47489 90)
			(size 0.519938 1.4986)
			(layers "F.Cu" "F.Mask" "F.Paste")
			(net "M_L_CPU1_SA_DQS_DP<1>")
		)
		(pad "23" smd rect
			(at -2.050034 -44.625006 90)
			(size 0.519938 1.4986)
			(layers "F.Cu" "F.Mask" "F.Paste")
			(net "M_L_CPU1_SA_DQS_DN<1>")
		)
		(pad "24" smd rect
			(at -2.050034 -43.775122 90)
			(size 0.519938 1.4986)
			(layers "F.Cu" "F.Mask" "F.Paste")
			(net "GND")
		)
		(pad "25" smd rect
			(at -2.050034 -42.924984 90)
			(size 0.519938 1.4986)
			(layers "F.Cu" "F.Mask" "F.Paste")
			(net "M_L_CPU1_SA_DQ<12>")
		)
		(pad "26" smd rect
			(at -2.050034 -42.0751 90)
			(size 0.519938 1.4986)
			(layers "F.Cu" "F.Mask" "F.Paste")
			(net "GND")
		)
		(pad "27" smd rect
			(at -2.050034 -41.224962 90)
			(size 0.519938 1.4986)
			(layers "F.Cu" "F.Mask" "F.Paste")
			(net "M_L_CPU1_SA_DQ<13>")
		)
		(pad "28" smd rect
			(at -2.050034 -40.375078 90)
			(size 0.519938 1.4986)
			(layers "F.Cu" "F.Mask" "F.Paste")
			(net "GND")
		)
		(pad "29" smd rect
			(at -2.050034 -39.52494 90)
			(size 0.519938 1.4986)
			(layers "F.Cu" "F.Mask" "F.Paste")
			(net "M_L_CPU1_SA_DQ<16>")
		)
		(pad "30" smd rect
			(at -2.050034 -38.675056 90)
			(size 0.519938 1.4986)
			(layers "F.Cu" "F.Mask" "F.Paste")
			(net "GND")
		)
		(pad "31" smd rect
			(at -2.050034 -37.824918 90)
			(size 0.519938 1.4986)
			(layers "F.Cu" "F.Mask" "F.Paste")
			(net "M_L_CPU1_SA_DQ<17>")
		)
		(pad "32" smd rect
			(at -2.050034 -36.975034 90)
			(size 0.519938 1.4986)
			(layers "F.Cu" "F.Mask" "F.Paste")
			(net "GND")
		)
		(pad "33" smd rect
			(at -2.050034 -36.124896 90)
			(size 0.519938 1.4986)
			(layers "F.Cu" "F.Mask" "F.Paste")
			(net "M_L_CPU1_SA_DQS_DP<2>")
		)
		(pad "34" smd rect
			(at -2.050034 -35.275012 90)
			(size 0.519938 1.4986)
			(layers "F.Cu" "F.Mask" "F.Paste")
			(net "M_L_CPU1_SA_DQS_DN<2>")
		)
		(pad "35" smd rect
			(at -2.050034 -34.425128 90)
			(size 0.519938 1.4986)
			(layers "F.Cu" "F.Mask" "F.Paste")
			(net "GND")
		)
		(pad "36" smd rect
			(at -2.050034 -33.57499 90)
			(size 0.519938 1.4986)
			(layers "F.Cu" "F.Mask" "F.Paste")
			(net "M_L_CPU1_SA_DQ<20>")
		)
		(pad "37" smd rect
			(at -2.050034 -32.725106 90)
			(size 0.519938 1.4986)
			(layers "F.Cu" "F.Mask" "F.Paste")
			(net "GND")
		)
		(pad "38" smd rect
			(at -2.050034 -31.874968 90)
			(size 0.519938 1.4986)
			(layers "F.Cu" "F.Mask" "F.Paste")
			(net "M_L_CPU1_SA_DQ<21>")
		)
		(pad "39" smd rect
			(at -2.050034 -31.025084 90)
			(size 0.519938 1.4986)
			(layers "F.Cu" "F.Mask" "F.Paste")
			(net "GND")
		)
		(pad "40" smd rect
			(at -2.050034 -30.174946 90)
			(size 0.519938 1.4986)
			(layers "F.Cu" "F.Mask" "F.Paste")
			(net "M_L_CPU1_SA_DQ<24>")
		)
		(pad "41" smd rect
			(at -2.050034 -29.325062 90)
			(size 0.519938 1.4986)
			(layers "F.Cu" "F.Mask" "F.Paste")
			(net "GND")
		)
		(pad "42" smd rect
			(at -2.050034 -28.474924 90)
			(size 0.519938 1.4986)
			(layers "F.Cu" "F.Mask" "F.Paste")
			(net "M_L_CPU1_SA_DQ<25>")
		)
		(pad "43" smd rect
			(at -2.050034 -27.62504 90)
			(size 0.519938 1.4986)
			(layers "F.Cu" "F.Mask" "F.Paste")
			(net "GND")
		)
		(pad "44" smd rect
			(at -2.050034 -26.774902 90)
			(size 0.519938 1.4986)
			(layers "F.Cu" "F.Mask" "F.Paste")
			(net "M_L_CPU1_SA_DQS_DP<3>")
		)
		(pad "45" smd rect
			(at -2.050034 -25.925018 90)
			(size 0.519938 1.4986)
			(layers "F.Cu" "F.Mask" "F.Paste")
			(net "M_L_CPU1_SA_DQS_DN<3>")
		)
		(pad "46" smd rect
			(at -2.050034 -25.07488 90)
			(size 0.519938 1.4986)
			(layers "F.Cu" "F.Mask" "F.Paste")
			(net "GND")
		)
		(pad "47" smd rect
			(at -2.050034 -24.224996 90)
			(size 0.519938 1.4986)
			(layers "F.Cu" "F.Mask" "F.Paste")
			(net "M_L_CPU1_SA_DQ<28>")
		)
		(pad "48" smd rect
			(at -2.050034 -23.375112 90)
			(size 0.519938 1.4986)
			(layers "F.Cu" "F.Mask" "F.Paste")
			(net "GND")
		)
		(pad "49" smd rect
			(at -2.050034 -22.524974 90)
			(size 0.519938 1.4986)
			(layers "F.Cu" "F.Mask" "F.Paste")
			(net "M_L_CPU1_SA_DQ<29>")
		)
		(pad "50" smd rect
			(at -2.050034 -21.67509 90)
			(size 0.519938 1.4986)
			(layers "F.Cu" "F.Mask" "F.Paste")
			(net "GND")
		)
		(pad "51" smd rect
			(at -2.050034 -20.824952 90)
			(size 0.519938 1.4986)
			(layers "F.Cu" "F.Mask" "F.Paste")
			(net "M_L_CPU1_SA_CB<0>")
		)
		(pad "52" smd rect
			(at -2.050034 -19.975068 90)
			(size 0.519938 1.4986)
			(layers "F.Cu" "F.Mask" "F.Paste")
			(net "GND")
		)
		(pad "53" smd rect
			(at -2.050034 -19.12493 90)
			(size 0.519938 1.4986)
			(layers "F.Cu" "F.Mask" "F.Paste")
			(net "M_L_CPU1_SA_CB<1>")
		)
		(pad "54" smd rect
			(at -2.050034 -18.275046 90)
			(size 0.519938 1.4986)
			(layers "F.Cu" "F.Mask" "F.Paste")
			(net "GND")
		)
		(pad "55" smd rect
			(at -2.050034 -17.424908 90)
			(size 0.519938 1.4986)
			(layers "F.Cu" "F.Mask" "F.Paste")
			(net "M_L_CPU1_SA_DQS_DP<4>")
		)
		(pad "56" smd rect
			(at -2.050034 -16.575024 90)
			(size 0.519938 1.4986)
			(layers "F.Cu" "F.Mask" "F.Paste")
			(net "M_L_CPU1_SA_DQS_DN<4>")
		)
		(pad "57" smd rect
			(at -2.050034 -15.724886 90)
			(size 0.519938 1.4986)
			(layers "F.Cu" "F.Mask" "F.Paste")
			(net "GND")
		)
		(pad "58" smd rect
			(at -2.050034 -14.875002 90)
			(size 0.519938 1.4986)
			(layers "F.Cu" "F.Mask" "F.Paste")
			(net "M_L_CPU1_SA_CB<4>")
		)
		(pad "59" smd rect
			(at -2.050034 -14.025118 90)
			(size 0.519938 1.4986)
			(layers "F.Cu" "F.Mask" "F.Paste")
			(net "GND")
		)
		(pad "60" smd rect
			(at -2.050034 -13.17498 90)
			(size 0.519938 1.4986)
			(layers "F.Cu" "F.Mask" "F.Paste")
			(net "M_L_CPU1_SA_CB<5>")
		)
		(pad "61" smd rect
			(at -2.050034 -12.325096 90)
			(size 0.519938 1.4986)
			(layers "F.Cu" "F.Mask" "F.Paste")
			(net "GND")
		)
		(pad "62" smd rect
			(at -2.050034 -11.474958 90)
			(size 0.519938 1.4986)
			(layers "F.Cu" "F.Mask" "F.Paste")
			(net "M_L_CPU1_ALERT_N")
		)
		(pad "63" smd rect
			(at -2.050034 -10.625074 90)
			(size 0.519938 1.4986)
			(layers "F.Cu" "F.Mask" "F.Paste")
			(net "GND")
		)
		(pad "64" smd rect
			(at -2.050034 -9.774936 90)
			(size 0.519938 1.4986)
			(layers "F.Cu" "F.Mask" "F.Paste")
			(net "M_L_CPU1_SA_CS_N<0>")
		)
		(pad "65" smd rect
			(at -2.050034 -8.925052 90)
			(size 0.519938 1.4986)
			(layers "F.Cu" "F.Mask" "F.Paste")
			(net "GND")
		)
		(pad "66" smd rect
			(at -2.050034 -8.074914 90)
			(size 0.519938 1.4986)
			(layers "F.Cu" "F.Mask" "F.Paste")
			(net "M_L_CPU1_SA_CA<0>")
		)
		(pad "67" smd rect
			(at -2.050034 -7.22503 90)
			(size 0.519938 1.4986)
			(layers "F.Cu" "F.Mask" "F.Paste")
			(net "GND")
		)
		(pad "68" smd rect
			(at -2.050034 -6.374892 90)
			(size 0.519938 1.4986)
			(layers "F.Cu" "F.Mask" "F.Paste")
			(net "M_L_CPU1_SA_CA<2>")
		)
		(pad "69" smd rect
			(at -2.050034 -5.525008 90)
			(size 0.519938 1.4986)
			(layers "F.Cu" "F.Mask" "F.Paste")
			(net "GND")
		)
		(pad "70" smd rect
			(at -2.050034 -4.675124 90)
			(size 0.519938 1.4986)
			(layers "F.Cu" "F.Mask" "F.Paste")
			(net "M_L_CPU1_SA_CA<4>")
		)
		(pad "71" smd rect
			(at -2.050034 -3.824986 90)
			(size 0.519938 1.4986)
			(layers "F.Cu" "F.Mask" "F.Paste")
			(net "GND")
		)
		(pad "72" smd rect
			(at -2.050034 -2.975102 90)
			(size 0.519938 1.4986)
			(layers "F.Cu" "F.Mask" "F.Paste")
			(net "M_L_CPU1_SA_CA<6>")
		)
		(pad "73" smd rect
			(at -2.050034 -2.124964 90)
			(size 0.519938 1.4986)
			(layers "F.Cu" "F.Mask" "F.Paste")
			(net "GND")
		)
		(pad "74" smd rect
			(at -2.050034 -1.27508 90)
			(size 0.519938 1.4986)
			(layers "F.Cu" "F.Mask" "F.Paste")
			(net "M_L_CPU1_SA_PAR")
		)
		(pad "75" smd rect
			(at -2.050034 -0.424942 90)
			(size 0.519938 1.4986)
			(layers "F.Cu" "F.Mask" "F.Paste")
			(net "GND")
		)
		(pad "76" smd rect
			(at -2.050034 5.525008 90)
			(size 0.519938 1.4986)
			(layers "F.Cu" "F.Mask" "F.Paste")
			(net "M_L_CPU1_SB_CA<0>")
		)
		(pad "77" smd rect
			(at -2.050034 6.374892 90)
			(size 0.519938 1.4986)
			(layers "F.Cu" "F.Mask" "F.Paste")
			(net "GND")
		)
		(pad "78" smd rect
			(at -2.050034 7.22503 90)
			(size 0.519938 1.4986)
			(layers "F.Cu" "F.Mask" "F.Paste")
			(net "M_L_CPU1_SB_CA<2>")
		)
		(pad "79" smd rect
			(at -2.050034 8.074914 90)
			(size 0.519938 1.4986)
			(layers "F.Cu" "F.Mask" "F.Paste")
			(net "GND")
		)
		(pad "80" smd rect
			(at -2.050034 8.925052 90)
			(size 0.519938 1.4986)
			(layers "F.Cu" "F.Mask" "F.Paste")
			(net "M_L_CPU1_SB_CA<4>")
		)
		(pad "81" smd rect
			(at -2.050034 9.774936 90)
			(size 0.519938 1.4986)
			(layers "F.Cu" "F.Mask" "F.Paste")
			(net "GND")
		)
		(pad "82" smd rect
			(at -2.050034 10.625074 90)
			(size 0.519938 1.4986)
			(layers "F.Cu" "F.Mask" "F.Paste")
			(net "M_L_CPU1_SB_CA<6>")
		)
		(pad "83" smd rect
			(at -2.050034 11.474958 90)
			(size 0.519938 1.4986)
			(layers "F.Cu" "F.Mask" "F.Paste")
			(net "GND")
		)
		(pad "84" smd rect
			(at -2.050034 12.325096 90)
			(size 0.519938 1.4986)
			(layers "F.Cu" "F.Mask" "F.Paste")
			(net "M_L_CPU1_SB_CS_N<0>")
		)
		(pad "85" smd rect
			(at -2.050034 13.17498 90)
			(size 0.519938 1.4986)
			(layers "F.Cu" "F.Mask" "F.Paste")
			(net "GND")
		)
		(pad "86" smd rect
			(at -2.050034 14.025118 90)
			(size 0.519938 1.4986)
			(layers "F.Cu" "F.Mask" "F.Paste")
			(net "M_L_CPU1_SA_RSP<0>")
		)
		(pad "87" smd rect
			(at -2.050034 14.875002 90)
			(size 0.519938 1.4986)
			(layers "F.Cu" "F.Mask" "F.Paste")
			(net "M_L_CPU1_SB_RSP<0>")
		)
		(pad "88" smd rect
			(at -2.050034 15.724886 90)
			(size 0.519938 1.4986)
			(layers "F.Cu" "F.Mask" "F.Paste")
			(net "GND")
		)
		(pad "89" smd rect
			(at -2.050034 16.575024 90)
			(size 0.519938 1.4986)
			(layers "F.Cu" "F.Mask" "F.Paste")
			(net "M_L_CPU1_SB_CB<4>")
		)
		(pad "90" smd rect
			(at -2.050034 17.424908 90)
			(size 0.519938 1.4986)
			(layers "F.Cu" "F.Mask" "F.Paste")
			(net "GND")
		)
		(pad "91" smd rect
			(at -2.050034 18.275046 90)
			(size 0.519938 1.4986)
			(layers "F.Cu" "F.Mask" "F.Paste")
			(net "M_L_CPU1_SB_CB<5>")
		)
		(pad "92" smd rect
			(at -2.050034 19.12493 90)
			(size 0.519938 1.4986)
			(layers "F.Cu" "F.Mask" "F.Paste")
			(net "GND")
		)
		(pad "93" smd rect
			(at -2.050034 19.975068 90)
			(size 0.519938 1.4986)
			(layers "F.Cu" "F.Mask" "F.Paste")
			(net "M_L_CPU1_SB_DQS_DP<9>")
		)
		(pad "94" smd rect
			(at -2.050034 20.824952 90)
			(size 0.519938 1.4986)
			(layers "F.Cu" "F.Mask" "F.Paste")
			(net "M_L_CPU1_SB_DQS_DN<9>")
		)
		(pad "95" smd rect
			(at -2.050034 21.67509 90)
			(size 0.519938 1.4986)
			(layers "F.Cu" "F.Mask" "F.Paste")
			(net "GND")
		)
		(pad "96" smd rect
			(at -2.050034 22.524974 90)
			(size 0.519938 1.4986)
			(layers "F.Cu" "F.Mask" "F.Paste")
			(net "M_L_CPU1_SB_CB<0>")
		)
		(pad "97" smd rect
			(at -2.050034 23.375112 90)
			(size 0.519938 1.4986)
			(layers "F.Cu" "F.Mask" "F.Paste")
			(net "GND")
		)
		(pad "98" smd rect
			(at -2.050034 24.224996 90)
			(size 0.519938 1.4986)
			(layers "F.Cu" "F.Mask" "F.Paste")
			(net "M_L_CPU1_SB_CB<1>")
		)
		(pad "99" smd rect
			(at -2.050034 25.07488 90)
			(size 0.519938 1.4986)
			(layers "F.Cu" "F.Mask" "F.Paste")
			(net "GND")
		)
		(pad "100" smd rect
			(at -2.050034 25.925018 90)
			(size 0.519938 1.4986)
			(layers "F.Cu" "F.Mask" "F.Paste")
			(net "M_L_CPU1_SB_DQ<0>")
		)
		(pad "101" smd rect
			(at -2.050034 26.774902 90)
			(size 0.519938 1.4986)
			(layers "F.Cu" "F.Mask" "F.Paste")
			(net "GND")
		)
		(pad "102" smd rect
			(at -2.050034 27.62504 90)
			(size 0.519938 1.4986)
			(layers "F.Cu" "F.Mask" "F.Paste")
			(net "M_L_CPU1_SB_DQ<1>")
		)
		(pad "103" smd rect
			(at -2.050034 28.474924 90)
			(size 0.519938 1.4986)
			(layers "F.Cu" "F.Mask" "F.Paste")
			(net "GND")
		)
		(pad "104" smd rect
			(at -2.050034 29.325062 90)
			(size 0.519938 1.4986)
			(layers "F.Cu" "F.Mask" "F.Paste")
			(net "M_L_CPU1_SB_DQS_DP<0>")
		)
		(pad "105" smd rect
			(at -2.050034 30.174946 90)
			(size 0.519938 1.4986)
			(layers "F.Cu" "F.Mask" "F.Paste")
			(net "M_L_CPU1_SB_DQS_DN<0>")
		)
		(pad "106" smd rect
			(at -2.050034 31.025084 90)
			(size 0.519938 1.4986)
			(layers "F.Cu" "F.Mask" "F.Paste")
			(net "GND")
		)
		(pad "107" smd rect
			(at -2.050034 31.874968 90)
			(size 0.519938 1.4986)
			(layers "F.Cu" "F.Mask" "F.Paste")
			(net "M_L_CPU1_SB_DQ<4>")
		)
		(pad "108" smd rect
			(at -2.050034 32.725106 90)
			(size 0.519938 1.4986)
			(layers "F.Cu" "F.Mask" "F.Paste")
			(net "GND")
		)
		(pad "109" smd rect
			(at -2.050034 33.57499 90)
			(size 0.519938 1.4986)
			(layers "F.Cu" "F.Mask" "F.Paste")
			(net "M_L_CPU1_SB_DQ<5>")
		)
		(pad "110" smd rect
			(at -2.050034 34.425128 90)
			(size 0.519938 1.4986)
			(layers "F.Cu" "F.Mask" "F.Paste")
			(net "GND")
		)
		(pad "111" smd rect
			(at -2.050034 35.275012 90)
			(size 0.519938 1.4986)
			(layers "F.Cu" "F.Mask" "F.Paste")
			(net "M_L_CPU1_SB_DQ<8>")
		)
		(pad "112" smd rect
			(at -2.050034 36.124896 90)
			(size 0.519938 1.4986)
			(layers "F.Cu" "F.Mask" "F.Paste")
			(net "GND")
		)
		(pad "113" smd rect
			(at -2.050034 36.975034 90)
			(size 0.519938 1.4986)
			(layers "F.Cu" "F.Mask" "F.Paste")
			(net "M_L_CPU1_SB_DQ<9>")
		)
	)
)
